# T6G (Grand Teton) — schematic netlist excerpt (pin names and nets, part order shuffled) for the footprints in the layout excerpt that follows; sources: Cadence DE-HDL packaged netlist, KiCad conversion of 04192023_DAF0TMB3IC0_F0TG_MB_C_brd_V02_OCP.brd

PC288  Q_CAP  22UF 4V 20% X6S  pkg C0805  page 209 : A = PVDD18_S5_P0 ; B = GND
C572  Q_CAP  4.7UF 6.3V 20% X6S  pkg 0402  page 279 : A = P0V9_CPU0_RT0_2A ; B = GND
C2576  Q_CAP  22UF 4V 20% X6S  pkg C0402  page 70 : A = PVDDCR_SOC_P0 ; B = GND

(kicad_pcb
	(version 20260206)
	(generator "pcbnew")
	(generator_version "10.0")
	(general
		(thickness 1.6)
		(legacy_teardrops no)
	)
	(paper "A4")
	(title_block
		(title "04192023_DAF0TMB3IC0_F0TG_MB_C_brd_V02_OCP.brd")
		(comment 1 "Grand Teton / footprints 6338-6340 of 8354")
	)
	(layers
		(0 "F.Cu" signal "TOP")
		(4 "In1.Cu" signal "GND")
		(6 "In2.Cu" signal "IN1")
		(8 "In3.Cu" signal "GND1")
		(10 "In4.Cu" signal "IN2")
		(12 "In5.Cu" signal "GND2")
		(14 "In6.Cu" signal "IN3")
		(16 "In7.Cu" signal "GND3")
		(18 "In8.Cu" signal "VCC")
		(20 "In9.Cu" signal "VCC1")
		(22 "In10.Cu" signal "GND4")
		(24 "In11.Cu" signal "IN4")
		(26 "In12.Cu" signal "GND5")
		(28 "In13.Cu" signal "IN5")
		(30 "In14.Cu" signal "GND6")
		(32 "In15.Cu" signal "IN6")
		(34 "In16.Cu" signal "GND7")
		(2 "B.Cu" signal "BOTTOM")
		(9 "F.Adhes" user "F.Adhesive")
		(11 "B.Adhes" user "B.Adhesive")
		(13 "F.Paste" user "Package Geometry/Pastemask Top")
		(15 "B.Paste" user "Package Geometry/Pastemask Bottom")
		(5 "F.SilkS" user "Ref Des/Silkscreen Top")
		(7 "B.SilkS" user "Ref Des/Silkscreen Bottom")
		(1 "F.Mask" user "Board Geometry/Soldermask Top")
		(3 "B.Mask" user "Board Geometry/Soldermask Bottom")
		(17 "Dwgs.User" user "User.Drawings")
		(19 "Cmts.User" user "User.Comments")
		(21 "Eco1.User" user "User.Eco1")
		(23 "Eco2.User" user "User.Eco2")
		(25 "Edge.Cuts" user "Board Geometry/Outline")
		(27 "Margin" user)
		(31 "F.CrtYd" user "Package Geometry/Place Bound Top")
		(29 "B.CrtYd" user "Package Geometry/Place Bound Bottom")
		(35 "F.Fab" user "Ref Des/Assembly Top")
		(33 "B.Fab" user "Ref Des/Assembly Bottom")
	)
	(footprint ""
		(layer "B.Cu")
		(at 354.152454 -251.78131)
		(property "Reference" "C2576"
			(at 0 0 0)
			(layer "B.SilkS")
			(hide yes)
			(effects
				(font
					(size 1.27 1.27)
				)
				(justify mirror)
			)
		)
		(property "Value" ""
			(at 0 0 0)
			(layer "B.Fab")
			(effects
				(font
					(size 1.27 1.27)
				)
				(justify mirror)
			)
		)
		(duplicate_pad_numbers_are_jumpers no)
		(fp_line
			(start -0.7874 -0.4064)
			(end -0.7874 0.4064)
			(stroke
				(width 0.1524)
				(type default)
			)
			(layer "B.SilkS")
		)
		(fp_line
			(start -0.7874 0.4064)
			(end 0.7874 0.4064)
			(stroke
				(width 0.1524)
				(type default)
			)
			(layer "B.SilkS")
		)
		(fp_line
			(start 0.7874 -0.4064)
			(end -0.7874 -0.4064)
			(stroke
				(width 0.1524)
				(type default)
			)
			(layer "B.SilkS")
		)
		(fp_line
			(start 0.7874 0.4064)
			(end 0.7874 -0.4064)
			(stroke
				(width 0.1524)
				(type default)
			)
			(layer "B.SilkS")
		)
		(fp_line
			(start -0.67945 -0.3048)
			(end -0.67945 0.3048)
			(stroke
				(width 0.1)
				(type default)
			)
			(layer "B.Fab")
		)
		(fp_line
			(start -0.67945 0.3048)
			(end -0.120396 0.3048)
			(stroke
				(width 0.1)
				(type default)
			)
			(layer "B.Fab")
		)
		(fp_line
			(start -0.12065 -0.3048)
			(end -0.67945 -0.3048)
			(stroke
				(width 0.1)
				(type default)
			)
			(layer "B.Fab")
		)
		(fp_line
			(start -0.12065 -0.2794)
			(end -0.12065 -0.3048)
			(stroke
				(width 0.1)
				(type default)
			)
			(layer "B.Fab")
		)
		(fp_line
			(start -0.120396 0.2794)
			(end 0.12065 0.2794)
			(stroke
				(width 0.1)
				(type default)
			)
			(layer "B.Fab")
		)
		(fp_line
			(start -0.120396 0.3048)
			(end -0.120396 0.2794)
			(stroke
				(width 0.1)
				(type default)
			)
			(layer "B.Fab")
		)
		(fp_line
			(start 0.12065 -0.305054)
			(end 0.12065 -0.2794)
			(stroke
				(width 0.1)
				(type default)
			)
			(layer "B.Fab")
		)
		(fp_line
			(start 0.12065 -0.2794)
			(end -0.12065 -0.2794)
			(stroke
				(width 0.1)
				(type default)
			)
			(layer "B.Fab")
		)
		(fp_line
			(start 0.12065 0.2794)
			(end 0.12065 0.3048)
			(stroke
				(width 0.1)
				(type default)
			)
			(layer "B.Fab")
		)
		(fp_line
			(start 0.12065 0.3048)
			(end 0.67945 0.3048)
			(stroke
				(width 0.1)
				(type default)
			)
			(layer "B.Fab")
		)
		(fp_line
			(start 0.67945 -0.305054)
			(end 0.12065 -0.305054)
			(stroke
				(width 0.1)
				(type default)
			)
			(layer "B.Fab")
		)
		(fp_line
			(start 0.67945 0.3048)
			(end 0.67945 -0.305054)
			(stroke
				(width 0.1)
				(type default)
			)
			(layer "B.Fab")
		)
		(pad "1" smd circle
			(at 0.40005 0 180)
			(size 0 0)
			(layers "B.Cu" "B.Mask" "B.Paste")
			(net "PVDDCR_SOC_P0")
		)
		(pad "2" smd circle
			(at -0.40005 0 180)
			(size 0 0)
			(layers "B.Cu" "B.Mask" "B.Paste")
			(net "GND")
		)
	)
	(footprint ""
		(layer "B.Cu")
		(at 337.661504 -151.064722 90)
		(property "Reference" "PC288"
			(at 0 0 90)
			(layer "B.SilkS")
			(hide yes)
			(effects
				(font
					(size 1.27 1.27)
				)
				(justify mirror)
			)
		)
		(property "Value" ""
			(at 0 0 90)
			(layer "B.Fab")
			(effects
				(font
					(size 1.27 1.27)
				)
				(justify mirror)
			)
		)
		(duplicate_pad_numbers_are_jumpers no)
		(fp_line
			(start 1.524 -0.762)
			(end -1.524 -0.762)
			(stroke
				(width 0.1524)
				(type default)
			)
			(layer "B.SilkS")
		)
		(fp_line
			(start -1.524 -0.762)
			(end -1.524 0.762)
			(stroke
				(width 0.1524)
				(type default)
			)
			(layer "B.SilkS")
		)
		(fp_line
			(start 1.524 0.762)
			(end 1.524 -0.762)
			(stroke
				(width 0.1524)
				(type default)
			)
			(layer "B.SilkS")
		)
		(fp_line
			(start -1.524 0.762)
			(end 1.524 0.762)
			(stroke
				(width 0.1524)
				(type default)
			)
			(layer "B.SilkS")
		)
		(fp_line
			(start 1.1049 -0.724916)
			(end 1.1049 0.724916)
			(stroke
				(width 0.1)
				(type default)
			)
			(layer "B.Fab")
		)
		(fp_line
			(start -1.1049 -0.724916)
			(end 1.1049 -0.724916)
			(stroke
				(width 0.1)
				(type default)
			)
			(layer "B.Fab")
		)
		(fp_line
			(start 1.1049 0.724916)
			(end -1.1049 0.724916)
			(stroke
				(width 0.1)
				(type default)
			)
			(layer "B.Fab")
		)
		(fp_line
			(start -1.1049 0.724916)
			(end -1.1049 -0.724916)
			(stroke
				(width 0.1)
				(type default)
			)
			(layer "B.Fab")
		)
		(pad "1" smd rect
			(at 0.889 0 90)
			(size 1.016 1.27)
			(layers "B.Cu" "B.Mask" "B.Paste")
			(net "PVDD18_S5_P0")
		)
		(pad "2" smd rect
			(at -0.889 0 90)
			(size 1.016 1.27)
			(layers "B.Cu" "B.Mask" "B.Paste")
			(net "GND")
		)
	)
	(footprint ""
		(layer "B.Cu")
		(at 316.590934 -398.942052 90)
		(property "Reference" "C572"
			(at 0 0 90)
			(layer "B.SilkS")
			(hide yes)
			(effects
				(font
					(size 1.27 1.27)
				)
				(justify mirror)
			)
		)
		(property "Value" ""
			(at 0 0 90)
			(layer "B.Fab")
			(effects
				(font
					(size 1.27 1.27)
				)
				(justify mirror)
			)
		)
		(duplicate_pad_numbers_are_jumpers no)
		(fp_line
			(start 0.7874 -0.4064)
			(end -0.7874 -0.4064)
			(stroke
				(width 0.1524)
				(type default)
			)
			(layer "B.SilkS")
		)
		(fp_line
			(start -0.7874 -0.4064)
			(end -0.7874 0.4064)
			(stroke
				(width 0.1524)
				(type default)
			)
			(layer "B.SilkS")
		)
		(fp_line
			(start 0.7874 0.4064)
			(end 0.7874 -0.4064)
			(stroke
				(width 0.1524)
				(type default)
			)
			(layer "B.SilkS")
		)
		(fp_line
			(start -0.7874 0.4064)
			(end 0.7874 0.4064)
			(stroke
				(width 0.1524)
				(type default)
			)
			(layer "B.SilkS")
		)
		(fp_line
			(start 0.67945 -0.305054)
			(end 0.12065 -0.305054)
			(stroke
				(width 0.1)
				(type default)
			)
			(layer "B.Fab")
		)
		(fp_line
			(start 0.12065 -0.305054)
			(end 0.12065 -0.2794)
			(stroke
				(width 0.1)
				(type default)
			)
			(layer "B.Fab")
		)
		(fp_line
			(start -0.12065 -0.3048)
			(end -0.67945 -0.3048)
			(stroke
				(width 0.1)
				(type default)
			)
			(layer "B.Fab")
		)
		(fp_line
			(start -0.67945 -0.3048)
			(end -0.67945 0.3048)
			(stroke
				(width 0.1)
				(type default)
			)
			(layer "B.Fab")
		)
		(fp_line
			(start 0.12065 -0.2794)
			(end -0.12065 -0.2794)
			(stroke
				(width 0.1)
				(type default)
			)
			(layer "B.Fab")
		)
		(fp_line
			(start -0.12065 -0.2794)
			(end -0.12065 -0.3048)
			(stroke
				(width 0.1)
				(type default)
			)
			(layer "B.Fab")
		)
		(fp_line
			(start 0.12065 0.2794)
			(end 0.12065 0.3048)
			(stroke
				(width 0.1)
				(type default)
			)
			(layer "B.Fab")
		)
		(fp_line
			(start -0.120396 0.2794)
			(end 0.12065 0.2794)
			(stroke
				(width 0.1)
				(type default)
			)
			(layer "B.Fab")
		)
		(fp_line
			(start 0.67945 0.3048)
			(end 0.67945 -0.305054)
			(stroke
				(width 0.1)
				(type default)
			)
			(layer "B.Fab")
		)
		(fp_line
			(start 0.12065 0.3048)
			(end 0.67945 0.3048)
			(stroke
				(width 0.1)
				(type default)
			)
			(layer "B.Fab")
		)
		(fp_line
			(start -0.120396 0.3048)
			(end -0.120396 0.2794)
			(stroke
				(width 0.1)
				(type default)
			)
			(layer "B.Fab")
		)
		(fp_line
			(start -0.67945 0.3048)
			(end -0.120396 0.3048)
			(stroke
				(width 0.1)
				(type default)
			)
			(layer "B.Fab")
		)
		(pad "1" smd circle
			(at 0.40005 0 270)
			(size 0 0)
			(layers "B.Cu" "B.Mask" "B.Paste")
			(net "P0V9_CPU0_RT0_2A")
		)
		(pad "2" smd circle
			(at -0.40005 0 270)
			(size 0 0)
			(layers "B.Cu" "B.Mask" "B.Paste")
			(net "GND")
		)
	)
)
